(kicad_pcb
	(version 20260206)
	(generator "pcbnew")
	(generator_version "10.0")
	(general
		(thickness 1.6)
		(legacy_teardrops no)
	)
	(paper "A4")
	(title_block
		(title "v1-chassis-manager — T6M_CM_d_v01_1031_1645.brd")
		(comment 1 "Open CloudServer (Microsoft) / footprints 1337-1345 of 2512")
	)
	(layers
		(0 "F.Cu" signal "TOP")
		(4 "In1.Cu" signal "GND1")
		(6 "In2.Cu" signal "IN1")
		(8 "In3.Cu" signal "VCC1")
		(10 "In4.Cu" signal "VCC2")
		(12 "In5.Cu" signal "GND2")
		(14 "In6.Cu" signal "IN2")
		(16 "In7.Cu" signal "IN3")
		(18 "In8.Cu" signal "GND3")
		(2 "B.Cu" signal "BOTTOM")
		(9 "F.Adhes" user "F.Adhesive")
		(11 "B.Adhes" user "B.Adhesive")
		(13 "F.Paste" user "Package Geometry/Pastemask Top")
		(15 "B.Paste" user "Package Geometry/Pastemask Bottom")
		(5 "F.SilkS" user "Ref Des/Silkscreen Top")
		(7 "B.SilkS" user "Ref Des/Silkscreen Bottom")
		(1 "F.Mask" user "Board Geometry/Soldermask Top")
		(3 "B.Mask" user "Board Geometry/Soldermask Bottom")
		(17 "Dwgs.User" user "User.Drawings")
		(19 "Cmts.User" user "User.Comments")
		(21 "Eco1.User" user "User.Eco1")
		(23 "Eco2.User" user "User.Eco2")
		(25 "Edge.Cuts" user "Board Geometry/Outline")
		(27 "Margin" user)
		(31 "F.CrtYd" user "Package Geometry/Place Bound Top")
		(29 "B.CrtYd" user "Package Geometry/Place Bound Bottom")
		(35 "F.Fab" user "Ref Des/Assembly Top")
		(33 "B.Fab" user "Ref Des/Assembly Bottom")
	)
	(footprint ""
		(layer "F.Cu")
		(at 15.88516 -41.795192)
		(property "Reference" "C499"
			(at -0.470916 7.61111 0)
			(unlocked yes)
			(layer "F.SilkS")
			(effects
				(font
					(size 0.7874 0.5842)
					(thickness 0.1524)
				)
			)
		)
		(property "Value" ""
			(at 0 0 0)
			(layer "F.Fab")
			(effects
				(font
					(size 1.27 1.27)
				)
			)
		)
		(duplicate_pad_numbers_are_jumpers no)
		(fp_line
			(start -1.2954 -0.5842)
			(end 1.2954 -0.5842)
			(stroke
				(width 0.1524)
				(type default)
			)
			(layer "F.SilkS")
		)
		(fp_line
			(start -1.2954 0.5842)
			(end -1.2954 -0.5842)
			(stroke
				(width 0.1524)
				(type default)
			)
			(layer "F.SilkS")
		)
		(fp_line
			(start 0 -0.5842)
			(end 0 0.5842)
			(stroke
				(width 0.1524)
				(type default)
			)
			(layer "F.SilkS")
		)
		(fp_line
			(start 1.2954 -0.5842)
			(end 1.2954 0.5842)
			(stroke
				(width 0.1524)
				(type default)
			)
			(layer "F.SilkS")
		)
		(fp_line
			(start 1.2954 0.5842)
			(end -1.2954 0.5842)
			(stroke
				(width 0.1524)
				(type default)
			)
			(layer "F.SilkS")
		)
		(fp_poly
			(pts
				(xy 0.8636 -0.4572) (xy 0.8636 -0.3556) (xy 1.143 -0.3556) (xy 1.143 0.3556) (xy 0.8636 0.3556)
				(xy 0.8636 0.4572) (xy -0.8636 0.4572) (xy -0.8636 0.3556) (xy -1.143 0.3556) (xy -1.143 -0.3556)
				(xy -0.8636 -0.3556) (xy -0.8636 -0.4572)
			)
			(stroke
				(width 0)
				(type default)
			)
			(fill no)
			(layer "F.CrtYd")
		)
		(fp_line
			(start -0.884936 -0.504952)
			(end 0.884936 -0.504952)
			(stroke
				(width 0.1)
				(type default)
			)
			(layer "F.Fab")
		)
		(fp_line
			(start -0.884936 0.504952)
			(end -0.884936 -0.504952)
			(stroke
				(width 0.1)
				(type default)
			)
			(layer "F.Fab")
		)
		(fp_line
			(start 0.884936 -0.504952)
			(end 0.884936 0.504952)
			(stroke
				(width 0.1)
				(type default)
			)
			(layer "F.Fab")
		)
		(fp_line
			(start 0.884936 0.504952)
			(end -0.884936 0.504952)
			(stroke
				(width 0.1)
				(type default)
			)
			(layer "F.Fab")
		)
		(pad "1" smd rect
			(at 0.7366 0 90)
			(size 0.7112 0.8128)
			(layers "F.Cu" "F.Mask" "F.Paste")
			(net "BMC_NODE1_GFX_RED")
		)
		(pad "2" smd rect
			(at -0.7366 0 90)
			(size 0.7112 0.8128)
			(layers "F.Cu" "F.Mask" "F.Paste")
			(net "GND")
		)
	)
	(footprint ""
		(layer "F.Cu")
		(at 73.39076 -185.205624 90)
		(property "Reference" "C707"
			(at 4.006088 -1.175258 90)
			(unlocked yes)
			(layer "F.SilkS")
			(effects
				(font
					(size 0.7874 0.5842)
					(thickness 0.1524)
				)
				(justify left)
			)
		)
		(property "Value" ""
			(at 0 0 90)
			(layer "F.Fab")
			(effects
				(font
					(size 1.27 1.27)
				)
			)
		)
		(duplicate_pad_numbers_are_jumpers no)
		(fp_line
			(start 0.7874 -0.4064)
			(end 0.7874 0.4064)
			(stroke
				(width 0.1524)
				(type default)
			)
			(layer "F.SilkS")
		)
		(fp_line
			(start -0.7874 -0.4064)
			(end 0.7874 -0.4064)
			(stroke
				(width 0.1524)
				(type default)
			)
			(layer "F.SilkS")
		)
		(fp_line
			(start 0 0.381)
			(end 0 -0.381)
			(stroke
				(width 0.1524)
				(type default)
			)
			(layer "F.SilkS")
		)
		(fp_line
			(start 0.7874 0.4064)
			(end -0.7874 0.4064)
			(stroke
				(width 0.1524)
				(type default)
			)
			(layer "F.SilkS")
		)
		(fp_line
			(start -0.7874 0.4064)
			(end -0.7874 -0.4064)
			(stroke
				(width 0.1524)
				(type default)
			)
			(layer "F.SilkS")
		)
		(fp_poly
			(pts
				(xy -0.5334 0.254) (xy -0.635 0.254) (xy -0.635 0.2286) (xy -0.635 -0.254) (xy -0.5334 -0.254) (xy -0.5334 -0.2794)
				(xy 0.5334 -0.2794) (xy 0.5334 -0.254) (xy 0.635 -0.254) (xy 0.635 0.254) (xy 0.5334 0.254) (xy 0.5334 0.2794)
				(xy -0.508 0.2794) (xy -0.5334 0.2794)
			)
			(stroke
				(width 0)
				(type default)
			)
			(fill no)
			(layer "F.CrtYd")
		)
		(pad "1" smd rect
			(at 0.40005 0 90)
			(size 0.4572 0.508)
			(layers "F.Cu" "F.Mask" "F.Paste")
			(net "UART_T4_NODE3_RXD")
		)
		(pad "2" smd rect
			(at -0.40005 0 90)
			(size 0.4572 0.508)
			(layers "F.Cu" "F.Mask" "F.Paste")
			(net "GND")
		)
	)
	(footprint ""
		(layer "F.Cu")
		(at 98.354134 -135.340852 90)
		(property "Reference" "C814"
			(at -2.155952 1.137412 90)
			(unlocked yes)
			(layer "F.SilkS")
			(effects
				(font
					(size 0.7874 0.5842)
					(thickness 0.1524)
				)
				(justify left)
			)
		)
		(property "Value" ""
			(at 0 0 90)
			(layer "F.Fab")
			(effects
				(font
					(size 1.27 1.27)
				)
			)
		)
		(duplicate_pad_numbers_are_jumpers no)
		(fp_line
			(start 0.7874 -0.4064)
			(end 0.7874 0.4064)
			(stroke
				(width 0.1524)
				(type default)
			)
			(layer "F.SilkS")
		)
		(fp_line
			(start -0.7874 -0.4064)
			(end 0.7874 -0.4064)
			(stroke
				(width 0.1524)
				(type default)
			)
			(layer "F.SilkS")
		)
		(fp_line
			(start 0 0.381)
			(end 0 -0.381)
			(stroke
				(width 0.1524)
				(type default)
			)
			(layer "F.SilkS")
		)
		(fp_line
			(start 0.7874 0.4064)
			(end -0.7874 0.4064)
			(stroke
				(width 0.1524)
				(type default)
			)
			(layer "F.SilkS")
		)
		(fp_line
			(start -0.7874 0.4064)
			(end -0.7874 -0.4064)
			(stroke
				(width 0.1524)
				(type default)
			)
			(layer "F.SilkS")
		)
		(fp_poly
			(pts
				(xy -0.5334 0.254) (xy -0.635 0.254) (xy -0.635 0.2286) (xy -0.635 -0.254) (xy -0.5334 -0.254) (xy -0.5334 -0.2794)
				(xy 0.5334 -0.2794) (xy 0.5334 -0.254) (xy 0.635 -0.254) (xy 0.635 0.254) (xy 0.5334 0.254) (xy 0.5334 0.2794)
				(xy -0.508 0.2794) (xy -0.5334 0.2794)
			)
			(stroke
				(width 0)
				(type default)
			)
			(fill no)
			(layer "F.CrtYd")
		)
		(pad "1" smd rect
			(at 0.40005 0 90)
			(size 0.4572 0.508)
			(layers "F.Cu" "F.Mask" "F.Paste")
			(net "P1V05_SUS_NODE1")
		)
		(pad "2" smd rect
			(at -0.40005 0 90)
			(size 0.4572 0.508)
			(layers "F.Cu" "F.Mask" "F.Paste")
			(net "GND")
		)
	)
	(footprint ""
		(layer "F.Cu")
		(at 128.25476 -185.205624 90)
		(property "Reference" "C761"
			(at 4.731258 0.173482 90)
			(unlocked yes)
			(layer "F.SilkS")
			(effects
				(font
					(size 0.7874 0.5842)
					(thickness 0.1524)
				)
				(justify left)
			)
		)
		(property "Value" ""
			(at 0 0 90)
			(layer "F.Fab")
			(effects
				(font
					(size 1.27 1.27)
				)
			)
		)
		(duplicate_pad_numbers_are_jumpers no)
		(fp_line
			(start 0.7874 -0.4064)
			(end 0.7874 0.4064)
			(stroke
				(width 0.1524)
				(type default)
			)
			(layer "F.SilkS")
		)
		(fp_line
			(start -0.7874 -0.4064)
			(end 0.7874 -0.4064)
			(stroke
				(width 0.1524)
				(type default)
			)
			(layer "F.SilkS")
		)
		(fp_line
			(start 0 0.381)
			(end 0 -0.381)
			(stroke
				(width 0.1524)
				(type default)
			)
			(layer "F.SilkS")
		)
		(fp_line
			(start 0.7874 0.4064)
			(end -0.7874 0.4064)
			(stroke
				(width 0.1524)
				(type default)
			)
			(layer "F.SilkS")
		)
		(fp_line
			(start -0.7874 0.4064)
			(end -0.7874 -0.4064)
			(stroke
				(width 0.1524)
				(type default)
			)
			(layer "F.SilkS")
		)
		(fp_poly
			(pts
				(xy -0.5334 0.254) (xy -0.635 0.254) (xy -0.635 0.2286) (xy -0.635 -0.254) (xy -0.5334 -0.254) (xy -0.5334 -0.2794)
				(xy 0.5334 -0.2794) (xy 0.5334 -0.254) (xy 0.635 -0.254) (xy 0.635 0.254) (xy 0.5334 0.254) (xy 0.5334 0.2794)
				(xy -0.508 0.2794) (xy -0.5334 0.2794)
			)
			(stroke
				(width 0)
				(type default)
			)
			(fill no)
			(layer "F.CrtYd")
		)
		(pad "1" smd rect
			(at 0.40005 0 90)
			(size 0.4572 0.508)
			(layers "F.Cu" "F.Mask" "F.Paste")
			(net "UART_T10_NODE4_RXD")
		)
		(pad "2" smd rect
			(at -0.40005 0 90)
			(size 0.4572 0.508)
			(layers "F.Cu" "F.Mask" "F.Paste")
			(net "GND")
		)
	)
	(footprint ""
		(layer "F.Cu")
		(at 46.573694 -102.399084 90)
		(property "Reference" "R199"
			(at -2.351532 -2.51841 90)
			(unlocked yes)
			(layer "F.SilkS")
			(effects
				(font
					(size 0.7874 0.5842)
					(thickness 0.1524)
				)
				(justify left)
			)
		)
		(property "Value" ""
			(at 0 0 90)
			(layer "F.Fab")
			(effects
				(font
					(size 1.27 1.27)
				)
			)
		)
		(duplicate_pad_numbers_are_jumpers no)
		(fp_line
			(start 0.7874 -0.4064)
			(end 0.7874 0.4064)
			(stroke
				(width 0.1524)
				(type default)
			)
			(layer "F.SilkS")
		)
		(fp_line
			(start -0.7874 -0.4064)
			(end 0.7874 -0.4064)
			(stroke
				(width 0.1524)
				(type default)
			)
			(layer "F.SilkS")
		)
		(fp_line
			(start 0.7874 0.4064)
			(end -0.7874 0.4064)
			(stroke
				(width 0.1524)
				(type default)
			)
			(layer "F.SilkS")
		)
		(fp_line
			(start -0.7874 0.4064)
			(end -0.7874 -0.4064)
			(stroke
				(width 0.1524)
				(type default)
			)
			(layer "F.SilkS")
		)
		(fp_poly
			(pts
				(xy -0.508 0.2794) (xy -0.508 0.2286) (xy -0.635 0.2286) (xy -0.635 -0.254) (xy -0.5334 -0.254)
				(xy -0.5334 -0.2794) (xy 0.5334 -0.2794) (xy 0.5334 -0.254) (xy 0.635 -0.254) (xy 0.635 0.254) (xy 0.5334 0.254)
				(xy 0.5334 0.2794)
			)
			(stroke
				(width 0)
				(type default)
			)
			(fill no)
			(layer "F.CrtYd")
		)
		(pad "1" smd rect
			(at 0.40005 0 90)
			(size 0.4572 0.508)
			(layers "F.Cu" "F.Mask" "F.Paste")
			(net "SMB_TEMP1_NODE1_ALERT_L")
		)
		(pad "2" smd rect
			(at -0.40005 0 90)
			(size 0.4572 0.508)
			(layers "F.Cu" "F.Mask" "F.Paste")
			(net "SMB_TEMP1_NODE1_ALERT_R_L")
		)
	)
	(footprint ""
		(layer "F.Cu")
		(at 139.236704 -71.254112)
		(property "Reference" "D5"
			(at -1.487932 -1.19634 0)
			(unlocked yes)
			(layer "F.SilkS")
			(effects
				(font
					(size 0.7874 0.5842)
					(thickness 0.1524)
				)
				(justify left)
			)
		)
		(property "Value" ""
			(at 0 0 0)
			(layer "F.Fab")
			(effects
				(font
					(size 1.27 1.27)
				)
			)
		)
		(duplicate_pad_numbers_are_jumpers no)
		(fp_line
			(start -1.3208 -0.5588)
			(end 1.3208 -0.5588)
			(stroke
				(width 0.1524)
				(type default)
			)
			(layer "F.SilkS")
		)
		(fp_line
			(start -1.3208 0.5588)
			(end -1.3208 -0.5588)
			(stroke
				(width 0.1524)
				(type default)
			)
			(layer "F.SilkS")
		)
		(fp_line
			(start 1.3208 -0.5588)
			(end 1.3208 0.5588)
			(stroke
				(width 0.1524)
				(type default)
			)
			(layer "F.SilkS")
		)
		(fp_line
			(start 1.3208 0.5588)
			(end -1.3208 0.5588)
			(stroke
				(width 0.1524)
				(type default)
			)
			(layer "F.SilkS")
		)
		(fp_line
			(start 1.4732 -0.5588)
			(end 1.4732 0.5588)
			(stroke
				(width 0.1524)
				(type default)
			)
			(layer "F.SilkS")
		)
		(fp_line
			(start 1.6256 0.5588)
			(end 1.6256 -0.5588)
			(stroke
				(width 0.1524)
				(type default)
			)
			(layer "F.SilkS")
		)
		(fp_line
			(start 1.778 -0.5588)
			(end 1.3208 -0.5588)
			(stroke
				(width 0.1524)
				(type default)
			)
			(layer "F.SilkS")
		)
		(fp_line
			(start 1.778 -0.5588)
			(end 1.778 0.5588)
			(stroke
				(width 0.1524)
				(type default)
			)
			(layer "F.SilkS")
		)
		(fp_line
			(start 1.778 0.5588)
			(end 1.3208 0.5588)
			(stroke
				(width 0.1524)
				(type default)
			)
			(layer "F.SilkS")
		)
		(fp_rect
			(start -1.1684 0.508)
			(end 1.1684 -0.508)
			(stroke
				(width 0)
				(type default)
			)
			(fill no)
			(layer "F.CrtYd")
		)
		(fp_text user "-"
			(at 2.606548 0.03937 0)
			(unlocked yes)
			(layer "F.SilkS")
			(effects
				(font
					(size 1.27 0.9652)
					(thickness 0.1524)
				)
				(justify left)
			)
		)
		(pad "A" smd rect
			(at -0.750062 0)
			(size 0.8128 0.8128)
			(layers "F.Cu" "F.Mask" "F.Paste")
			(net "LED_SATA_NODE1_R")
		)
		(pad "C" smd rect
			(at 0.750062 0)
			(size 0.8128 0.8128)
			(layers "F.Cu" "F.Mask" "F.Paste")
			(net "LED_SATA_NODE1_GPIO0")
		)
	)
	(footprint ""
		(layer "F.Cu")
		(at 43.551602 -165.971982)
		(property "Reference" "Y4"
			(at -4.964938 -0.075438 0)
			(unlocked yes)
			(layer "F.SilkS")
			(effects
				(font
					(size 0.7874 0.5842)
					(thickness 0.1524)
				)
				(justify left)
			)
		)
		(property "Value" ""
			(at 0 0 0)
			(layer "F.Fab")
			(effects
				(font
					(size 1.27 1.27)
				)
			)
		)
		(duplicate_pad_numbers_are_jumpers no)
		(fp_line
			(start -3.3528 -1.700022)
			(end 3.3528 -1.700022)
			(stroke
				(width 0.1524)
				(type default)
			)
			(layer "F.SilkS")
		)
		(fp_line
			(start -3.3528 1.700022)
			(end -3.3528 -1.700022)
			(stroke
				(width 0.1524)
				(type default)
			)
			(layer "F.SilkS")
		)
		(fp_line
			(start 3.3528 -1.700022)
			(end 3.3528 1.700022)
			(stroke
				(width 0.1524)
				(type default)
			)
			(layer "F.SilkS")
		)
		(fp_line
			(start 3.3528 1.700022)
			(end -3.3528 1.700022)
			(stroke
				(width 0.1524)
				(type default)
			)
			(layer "F.SilkS")
		)
		(fp_poly
			(pts
				(xy -2.599944 1.700022) (xy 2.599944 1.700022) (xy 2.599944 1.1176) (xy 3.2258 1.1176) (xy 3.2258 -1.1176)
				(xy 2.599944 -1.1176) (xy 2.599944 -1.700022) (xy -2.599944 -1.700022) (xy -2.599944 -1.1176) (xy -3.2258 -1.1176)
				(xy -3.2258 1.1176) (xy -2.599944 1.1176)
			)
			(stroke
				(width 0)
				(type default)
			)
			(fill no)
			(layer "F.CrtYd")
		)
		(fp_line
			(start -2.599944 -1.700022)
			(end 2.599944 -1.700022)
			(stroke
				(width 0.1)
				(type default)
			)
			(layer "F.Fab")
		)
		(fp_line
			(start -2.599944 1.700022)
			(end -2.599944 -1.700022)
			(stroke
				(width 0.1)
				(type default)
			)
			(layer "F.Fab")
		)
		(fp_line
			(start 2.599944 -1.700022)
			(end 2.599944 1.700022)
			(stroke
				(width 0.1)
				(type default)
			)
			(layer "F.Fab")
		)
		(fp_line
			(start 2.599944 1.700022)
			(end -2.599944 1.700022)
			(stroke
				(width 0.1)
				(type default)
			)
			(layer "F.Fab")
		)
		(pad "1" smd rect
			(at -2.100072 0)
			(size 2.2098 2.2098)
			(layers "F.Cu" "F.Mask" "F.Paste")
			(net "LAN1_XTAL_IN")
		)
		(pad "2" smd rect
			(at 2.100072 0)
			(size 2.2098 2.2098)
			(layers "F.Cu" "F.Mask" "F.Paste")
			(net "LAN1_XTAL_OUT")
		)
	)
	(footprint ""
		(layer "F.Cu")
		(at 176.90465 -55.084472 180)
		(property "Reference" "C560"
			(at 3.75666 2.276094 0)
			(unlocked yes)
			(layer "F.SilkS")
			(effects
				(font
					(size 0.7874 0.5842)
					(thickness 0.1524)
				)
				(justify left)
			)
		)
		(property "Value" ""
			(at 0 0 180)
			(layer "F.Fab")
			(effects
				(font
					(size 1.27 1.27)
				)
			)
		)
		(duplicate_pad_numbers_are_jumpers no)
		(fp_line
			(start 0.7874 0.4064)
			(end -0.7874 0.4064)
			(stroke
				(width 0.1524)
				(type default)
			)
			(layer "F.SilkS")
		)
		(fp_line
			(start 0.7874 -0.4064)
			(end 0.7874 0.4064)
			(stroke
				(width 0.1524)
				(type default)
			)
			(layer "F.SilkS")
		)
		(fp_line
			(start 0 0.381)
			(end 0 -0.381)
			(stroke
				(width 0.1524)
				(type default)
			)
			(layer "F.SilkS")
		)
		(fp_line
			(start -0.7874 0.4064)
			(end -0.7874 -0.4064)
			(stroke
				(width 0.1524)
				(type default)
			)
			(layer "F.SilkS")
		)
		(fp_line
			(start -0.7874 -0.4064)
			(end 0.7874 -0.4064)
			(stroke
				(width 0.1524)
				(type default)
			)
			(layer "F.SilkS")
		)
		(fp_poly
			(pts
				(xy -0.5334 0.254) (xy -0.635 0.254) (xy -0.635 0.2286) (xy -0.635 -0.254) (xy -0.5334 -0.254) (xy -0.5334 -0.2794)
				(xy 0.5334 -0.2794) (xy 0.5334 -0.254) (xy 0.635 -0.254) (xy 0.635 0.254) (xy 0.5334 0.254) (xy 0.5334 0.2794)
				(xy -0.508 0.2794) (xy -0.5334 0.2794)
			)
			(stroke
				(width 0)
				(type default)
			)
			(fill no)
			(layer "F.CrtYd")
		)
		(pad "1" smd rect
			(at 0.40005 0 180)
			(size 0.4572 0.508)
			(layers "F.Cu" "F.Mask" "F.Paste")
			(net "USBPWR_P1")
		)
		(pad "2" smd rect
			(at -0.40005 0 180)
			(size 0.4572 0.508)
			(layers "F.Cu" "F.Mask" "F.Paste")
			(net "GND")
		)
	)
	(footprint ""
		(layer "F.Cu")
		(at 106.07421 -141.990318)
		(property "Reference" "PR74"
			(at -1.350518 -3.101594 0)
			(unlocked yes)
			(layer "F.SilkS")
			(effects
				(font
					(size 0.635 0.4064)
					(thickness 0.1524)
				)
				(justify left)
			)
		)
		(property "Value" ""
			(at 0 0 0)
			(layer "F.Fab")
			(effects
				(font
					(size 1.27 1.27)
				)
			)
		)
		(duplicate_pad_numbers_are_jumpers no)
		(fp_line
			(start -0.7874 -0.4064)
			(end 0.7874 -0.4064)
			(stroke
				(width 0.1524)
				(type default)
			)
			(layer "F.SilkS")
		)
		(fp_line
			(start -0.7874 0.4064)
			(end -0.7874 -0.4064)
			(stroke
				(width 0.1524)
				(type default)
			)
			(layer "F.SilkS")
		)
		(fp_line
			(start 0.7874 -0.4064)
			(end 0.7874 0.4064)
			(stroke
				(width 0.1524)
				(type default)
			)
			(layer "F.SilkS")
		)
		(fp_line
			(start 0.7874 0.4064)
			(end -0.7874 0.4064)
			(stroke
				(width 0.1524)
				(type default)
			)
			(layer "F.SilkS")
		)
		(fp_poly
			(pts
				(xy -0.508 0.2794) (xy -0.508 0.2286) (xy -0.635 0.2286) (xy -0.635 -0.254) (xy -0.5334 -0.254)
				(xy -0.5334 -0.2794) (xy 0.5334 -0.2794) (xy 0.5334 -0.254) (xy 0.635 -0.254) (xy 0.635 0.254) (xy 0.5334 0.254)
				(xy 0.5334 0.2794)
			)
			(stroke
				(width 0)
				(type default)
			)
			(fill no)
			(layer "F.CrtYd")
		)
		(pad "1" smd rect
			(at 0.40005 0)
			(size 0.4572 0.508)
			(layers "F.Cu" "F.Mask" "F.Paste")
			(net "VR_PVCCP_NODE1_TSEN")
		)
		(pad "2" smd rect
			(at -0.40005 0)
			(size 0.4572 0.508)
			(layers "F.Cu" "F.Mask" "F.Paste")
			(net "AGND_PVCCP_NODE1")
		)
	)
)
